# BASEBOARD_FAB2 (Tioga Pass) — schematic netlist excerpt (pin names and nets, part order shuffled) for the footprints in the layout excerpt that follows; sources: Cadence DE-HDL packaged netlist, KiCad conversion of Wiwynn_Tioga_Pass_MB.brd

C7W11  SC22U16V5MX-4-GP  20%  pkg SMD-BCG5  page 220 : \1\ = VR_FET_SW_P12V_STBY_PVDDQ_DEF ; \2\ = GND
R7M2  RES  240 1.0% CHIP  pkg 0402  page 99 : A = PVCCIO_CPU1 ; B = SMB_DDR_KLM_SCL_G
C5T13  CAP_A  47UF 4V 20% X5R  pkg 0603V  page 217 : A = PVDDQ_ABC ; B = GND

(kicad_pcb
	(version 20260206)
	(generator "pcbnew")
	(generator_version "10.0")
	(general
		(thickness 1.6)
		(legacy_teardrops no)
	)
	(paper "A4")
	(title_block
		(title "Wiwynn_Tioga_Pass_MB.brd")
		(comment 1 "Tioga Pass / footprints 3774-3776 of 4770")
	)
	(layers
		(0 "F.Cu" signal "TOP")
		(4 "In1.Cu" signal "L2GND")
		(6 "In2.Cu" signal "L3")
		(8 "In3.Cu" signal "L4GND")
		(10 "In4.Cu" signal "L5")
		(12 "In5.Cu" signal "L6GND")
		(14 "In6.Cu" signal "L7VCC")
		(16 "In7.Cu" signal "L8VCC")
		(18 "In8.Cu" signal "L9GND")
		(20 "In9.Cu" signal "L10")
		(22 "In10.Cu" signal "L11GND")
		(24 "In11.Cu" signal "L12")
		(26 "In12.Cu" signal "L13GND")
		(2 "B.Cu" signal "BOTTOM")
		(9 "F.Adhes" user "F.Adhesive")
		(11 "B.Adhes" user "B.Adhesive")
		(13 "F.Paste" user "Package Geometry/Pastemask Top")
		(15 "B.Paste" user "Package Geometry/Pastemask Bottom")
		(5 "F.SilkS" user "Ref Des/Silkscreen Top")
		(7 "B.SilkS" user "Ref Des/Silkscreen Bottom")
		(1 "F.Mask" user "Board Geometry/Soldermask Top")
		(3 "B.Mask" user "Board Geometry/Soldermask Bottom")
		(17 "Dwgs.User" user "User.Drawings")
		(19 "Cmts.User" user "User.Comments")
		(21 "Eco1.User" user "User.Eco1")
		(23 "Eco2.User" user "User.Eco2")
		(25 "Edge.Cuts" user "Board Geometry/Outline")
		(27 "Margin" user)
		(31 "F.CrtYd" user "Package Geometry/Place Bound Top")
		(29 "B.CrtYd" user "Package Geometry/Place Bound Bottom")
		(35 "F.Fab" user "Ref Des/Assembly Top")
		(33 "B.Fab" user "Ref Des/Assembly Bottom")
	)
	(footprint ""
		(layer "B.Cu")
		(at 258.445 -17.6276 -90)
		(property "Reference" "C5T13"
			(at 0 0 90)
			(layer "B.SilkS")
			(hide yes)
			(effects
				(font
					(size 1.27 1.27)
				)
				(justify mirror)
			)
		)
		(property "Value" ""
			(at 0 0 90)
			(layer "B.Fab")
			(effects
				(font
					(size 1.27 1.27)
				)
				(justify mirror)
			)
		)
		(duplicate_pad_numbers_are_jumpers no)
		(fp_rect
			(start 0.500126 1.598422)
			(end -0.500126 -0.201422)
			(stroke
				(width 0)
				(type default)
			)
			(fill no)
			(layer "B.CrtYd")
		)
		(fp_line
			(start -0.500126 1.598422)
			(end 0.500126 1.598422)
			(stroke
				(width 0.1)
				(type default)
			)
			(layer "B.Fab")
		)
		(fp_line
			(start 0.500126 1.598422)
			(end 0.500126 -0.201422)
			(stroke
				(width 0.1)
				(type default)
			)
			(layer "B.Fab")
		)
		(fp_line
			(start -0.500126 -0.201422)
			(end -0.500126 1.598422)
			(stroke
				(width 0.1)
				(type default)
			)
			(layer "B.Fab")
		)
		(fp_line
			(start 0.500126 -0.201422)
			(end -0.500126 -0.201422)
			(stroke
				(width 0.1)
				(type default)
			)
			(layer "B.Fab")
		)
		(pad "1" smd rect
			(at 0 0 180)
			(size 0.889 0.9906)
			(layers "B.Cu" "B.Mask" "B.Paste")
			(net "PVDDQ_ABC")
		)
		(pad "2" smd rect
			(at 0 1.397 180)
			(size 0.889 0.9906)
			(layers "B.Cu" "B.Mask" "B.Paste")
			(net "GND")
		)
		(zone
			(layer "B.Cu")
			(hatch none 0.5)
			(connect_pads
				(clearance 0)
			)
			(min_thickness 0.25)
			(keepout
				(tracks not_allowed)
				(vias allowed)
				(pads allowed)
				(copperpour not_allowed)
				(footprints allowed)
			)
			(placement
				(enabled no)
				(sheetname "")
			)
			(fill
				(thermal_gap 0.5)
				(thermal_bridge_width 0.5)
				(island_removal_mode 0)
			)
			(polygon
				(pts
					(xy 257.4925 -17.1323) (xy 258.0005 -17.1323) (xy 258.0005 -18.1229) (xy 257.4925 -18.1229)
				)
			)
		)
		(zone
			(layer "B.Cu")
			(hatch none 0.5)
			(connect_pads
				(clearance 0)
			)
			(min_thickness 0.25)
			(keepout
				(tracks allowed)
				(vias not_allowed)
				(pads allowed)
				(copperpour not_allowed)
				(footprints allowed)
			)
			(placement
				(enabled no)
				(sheetname "")
			)
			(fill
				(thermal_gap 0.5)
				(thermal_bridge_width 0.5)
				(island_removal_mode 0)
			)
			(polygon
				(pts
					(xy 257.4925 -17.1323) (xy 258.0005 -17.1323) (xy 258.0005 -18.1229) (xy 257.4925 -18.1229)
				)
			)
		)
	)
	(footprint ""
		(layer "B.Cu")
		(at 353.64801 -141.689328 90)
		(property "Reference" "C7W11"
			(at 0 0 90)
			(layer "B.SilkS")
			(hide yes)
			(effects
				(font
					(size 1.27 1.27)
				)
				(justify mirror)
			)
		)
		(property "Value" "*"
			(at 0.0762 -6.2357 90)
			(unlocked yes)
			(layer "B.Fab")
			(hide yes)
			(effects
				(font
					(size 1.27 1.016)
					(thickness 0.1524)
				)
				(justify mirror)
			)
		)
		(property "Device Type" "SC22U16V5MX-4-GP_SMD-BCG5-SC22A"
			(at 0.0762 -8.2677 90)
			(unlocked yes)
			(layer "B.Fab")
			(hide yes)
			(effects
				(font
					(size 1.27 1.016)
					(thickness 0.1524)
				)
				(justify mirror)
			)
		)
		(duplicate_pad_numbers_are_jumpers no)
		(fp_line
			(start -0.635 0)
			(end 0.635 0)
			(stroke
				(width 0.508)
				(type default)
			)
			(layer "B.SilkS")
		)
		(fp_rect
			(start 0.9652 1.778)
			(end -0.9652 -1.778)
			(stroke
				(width 0)
				(type default)
			)
			(fill no)
			(layer "B.CrtYd")
		)
		(fp_poly
			(pts
				(xy 0.9652 -1.778) (xy -0.9652 -1.778) (xy -0.9652 1.778) (xy 0.9652 1.778)
			)
			(stroke
				(width 0)
				(type default)
			)
			(fill no)
			(layer "B.Fab")
		)
		(pad "1" smd rect
			(at 0 -0.9652 270)
			(size 1.397 1.143)
			(layers "B.Cu" "B.Mask" "B.Paste")
			(net "VR_FET_SW_P12V_STBY_PVDDQ_DEF")
		)
		(pad "2" smd rect
			(at 0 0.9652 270)
			(size 1.397 1.143)
			(layers "B.Cu" "B.Mask" "B.Paste")
			(net "GND")
		)
	)
	(footprint ""
		(layer "B.Cu")
		(at 157.08122 -124.0917)
		(property "Reference" "R7M2"
			(at 0 0 0)
			(layer "B.SilkS")
			(hide yes)
			(effects
				(font
					(size 1.27 1.27)
				)
				(justify mirror)
			)
		)
		(property "Value" ""
			(at 0 0 0)
			(layer "B.Fab")
			(effects
				(font
					(size 1.27 1.27)
				)
				(justify mirror)
			)
		)
		(duplicate_pad_numbers_are_jumpers no)
		(fp_poly
			(pts
				(xy 0.2794 -0.1016) (xy -0.2794 -0.1016) (xy -0.2794 0.9906) (xy 0.2794 0.9906)
			)
			(stroke
				(width 0)
				(type default)
			)
			(fill no)
			(layer "B.CrtYd")
		)
		(fp_line
			(start -0.2794 -0.1016)
			(end 0.2794 -0.1016)
			(stroke
				(width 0.1)
				(type default)
			)
			(layer "B.Fab")
		)
		(fp_line
			(start -0.2794 0.9906)
			(end -0.2794 -0.1016)
			(stroke
				(width 0.1)
				(type default)
			)
			(layer "B.Fab")
		)
		(fp_line
			(start 0.2794 -0.1016)
			(end 0.2794 0.9906)
			(stroke
				(width 0.1)
				(type default)
			)
			(layer "B.Fab")
		)
		(fp_line
			(start 0.2794 0.9906)
			(end -0.2794 0.9906)
			(stroke
				(width 0.1)
				(type default)
			)
			(layer "B.Fab")
		)
		(pad "1" smd rect
			(at 0 0 180)
			(size 0.508 0.508)
			(layers "B.Cu" "B.Mask" "B.Paste")
			(net "PVCCIO_CPU1")
		)
		(pad "2" smd rect
			(at 0 0.889 180)
			(size 0.508 0.508)
			(layers "B.Cu" "B.Mask" "B.Paste")
			(net "SMB_DDR_KLM_SCL_G")
		)
		(zone
			(layer "B.Cu")
			(hatch none 0.5)
			(connect_pads
				(clearance 0)
			)
			(min_thickness 0.25)
			(keepout
				(tracks allowed)
				(vias not_allowed)
				(pads allowed)
				(copperpour not_allowed)
				(footprints allowed)
			)
			(placement
				(enabled no)
				(sheetname "")
			)
			(fill
				(thermal_gap 0.5)
				(thermal_bridge_width 0.5)
				(island_removal_mode 0)
			)
			(polygon
				(pts
					(xy 157.33522 -123.8377) (xy 156.82722 -123.8377) (xy 156.82722 -123.4567) (xy 157.33522 -123.4567)
				)
			)
		)
		(zone
			(layer "B.Cu")
			(hatch none 0.5)
			(connect_pads
				(clearance 0)
			)
			(min_thickness 0.25)
			(keepout
				(tracks not_allowed)
				(vias allowed)
				(pads allowed)
				(copperpour not_allowed)
				(footprints allowed)
			)
			(placement
				(enabled no)
				(sheetname "")
			)
			(fill
				(thermal_gap 0.5)
				(thermal_bridge_width 0.5)
				(island_removal_mode 0)
			)
			(polygon
				(pts
					(xy 157.33522 -123.4567) (xy 156.82722 -123.4567) (xy 156.82722 -123.8377) (xy 157.33522 -123.8377)
				)
			)
		)
	)
)
